(kicad_pcb
	(version 20241229)
	(generator "pcbnew")
	(generator_version "9.0")
	(general
		(thickness 1.552)
		(legacy_teardrops no)
	)
	(paper "A4")
	(title_block
		(date "2023-07-25")
		(rev "1.1.4")
		(comment 9 "footprints 144-148 of 379")
	)
	(layers
		(0 "F.Cu" signal)
		(4 "In1.Cu" signal)
		(6 "In2.Cu" signal)
		(8 "In3.Cu" signal)
		(10 "In4.Cu" signal)
		(12 "In5.Cu" signal)
		(14 "In6.Cu" signal)
		(2 "B.Cu" signal)
		(9 "F.Adhes" user "F.Adhesive")
		(11 "B.Adhes" user "B.Adhesive")
		(13 "F.Paste" user)
		(15 "B.Paste" user)
		(5 "F.SilkS" user "F.Silkscreen")
		(7 "B.SilkS" user "B.Silkscreen")
		(1 "F.Mask" user)
		(3 "B.Mask" user)
		(17 "Dwgs.User" user "User.Drawings")
		(19 "Cmts.User" user "User.Comments")
		(21 "Eco1.User" user "User.Eco1")
		(23 "Eco2.User" user "User.Eco2")
		(25 "Edge.Cuts" user)
		(27 "Margin" user)
		(31 "F.CrtYd" user "F.Courtyard")
		(29 "B.CrtYd" user "B.Courtyard")
		(35 "F.Fab" user)
		(33 "B.Fab" user)
	)
	(footprint "antmicro-footprints:R_0402_1005Metric"
		(layer "F.Cu")
		(at 144.28 76.19)
		(descr "Resistor SMD 0402")
		(tags "resistor SMD 0402")
		(property "Reference" "R22"
			(at -3.05 0.44 0)
			(layer "F.SilkS")
			(effects
				(font
					(size 0.65 0.65)
					(thickness 0.15)
				)
				(justify left bottom)
			)
		)
		(property "Value" "R_3k01_0402"
			(at 0 1.4 0)
			(layer "F.Fab")
			(hide yes)
			(effects
				(font
					(size 0.7 0.7)
					(thickness 0.15)
				)
				(justify left bottom)
			)
		)
		(property "Datasheet" "https://www.bourns.com/docs/product-datasheets/cr.pdf"
			(at 0 0 0)
			(layer "F.Fab")
			(hide yes)
			(effects
				(font
					(size 1.27 1.27)
					(thickness 0.15)
				)
			)
		)
		(property "Description" "SMD Chip Resistor, 3.01 kohm, ± 1%, 62.5 mW, 0402 [1005 Metric], Thick Film, General Purpose"
			(at 0 0 0)
			(layer "F.Fab")
			(hide yes)
			(effects
				(font
					(size 1.27 1.27)
					(thickness 0.15)
				)
			)
		)
		(property "Author" "Antmicro"
			(at 0 0 0)
			(layer "F.Fab")
			(hide yes)
			(effects
				(font
					(size 1 1)
					(thickness 0.15)
				)
			)
		)
		(property "License" "Apache-2.0"
			(at 0 0 0)
			(layer "F.Fab")
			(hide yes)
			(effects
				(font
					(size 1 1)
					(thickness 0.15)
				)
			)
		)
		(property "MPN" "CR0402-FX-3011GLF"
			(at 0 0 0)
			(layer "F.Fab")
			(hide yes)
			(effects
				(font
					(size 1 1)
					(thickness 0.15)
				)
			)
		)
		(property "Manufacturer" "Bourns"
			(at 0 0 0)
			(layer "F.Fab")
			(hide yes)
			(effects
				(font
					(size 1 1)
					(thickness 0.15)
				)
			)
		)
		(property "Tolerance" "1%"
			(at 0 0 0)
			(layer "F.Fab")
			(hide yes)
			(effects
				(font
					(size 1 1)
					(thickness 0.15)
				)
			)
		)
		(property "Val" "3k01"
			(at 0 0 0)
			(layer "F.Fab")
			(hide yes)
			(effects
				(font
					(size 1 1)
					(thickness 0.15)
				)
			)
		)
		(sheetname "/Power Supply/")
		(sheetfile "supply.kicad_sch")
		(attr smd)
		(fp_rect
			(start -0.925 -0.47)
			(end 0.925 0.47)
			(stroke
				(width 0.05)
				(type default)
			)
			(fill no)
			(layer "F.CrtYd")
		)
		(fp_rect
			(start -0.5 -0.25)
			(end 0.5 0.25)
			(stroke
				(width 0.15)
				(type solid)
			)
			(fill no)
			(layer "F.Fab")
		)
		(fp_text user "${REFERENCE}"
			(at -0.95 3.168 0)
			(layer "F.Fab")
			(effects
				(font
					(size 0.7 0.7)
					(thickness 0.15)
				)
				(justify left bottom)
			)
		)
		(fp_text user "Author: Antmicro"
			(at -0.95 4.169 0)
			(layer "F.Fab")
			(effects
				(font
					(size 0.7 0.7)
					(thickness 0.15)
				)
				(justify left bottom)
			)
		)
		(fp_text user "License: Apache-2.0"
			(at -0.95 5.169 0)
			(layer "F.Fab")
			(effects
				(font
					(size 0.7 0.7)
					(thickness 0.15)
				)
				(justify left bottom)
			)
		)
		(pad "1" smd roundrect
			(at -0.48 0)
			(size 0.59 0.64)
			(layers "F.Cu" "F.Mask" "F.Paste")
			(roundrect_rratio 0.25)
			(net 267 "Net-(U5-FB)")
			(pintype "passive")
		)
		(pad "2" smd roundrect
			(at 0.48 0)
			(size 0.59 0.64)
			(layers "F.Cu" "F.Mask" "F.Paste")
			(roundrect_rratio 0.25)
			(net 273 "/Power Supply/1V0_OUT")
			(pintype "passive")
		)
	)
	(footprint "antmicro-footprints:R_0402_1005Metric"
		(layer "F.Cu")
		(at 167.2 94.6)
		(descr "Resistor SMD 0402")
		(tags "resistor SMD 0402")
		(property "Reference" "R121"
			(at -3.67 0.34 0)
			(layer "F.SilkS")
			(effects
				(font
					(size 0.65 0.65)
					(thickness 0.15)
				)
				(justify left bottom)
			)
		)
		(property "Value" "R_0R_0402"
			(at 0 1.4 0)
			(layer "F.Fab")
			(hide yes)
			(effects
				(font
					(size 0.7 0.7)
					(thickness 0.15)
				)
				(justify left bottom)
			)
		)
		(property "Datasheet" "https://industrial.panasonic.com/cdbs/www-data/pdf/RDA0000/AOA0000C301.pdf"
			(at 0 0 0)
			(layer "F.Fab")
			(hide yes)
			(effects
				(font
					(size 1.27 1.27)
					(thickness 0.15)
				)
			)
		)
		(property "Description" "SMD Chip Resistor, Jumper, 0 ohm, 100 mW, 0402 [1005 Metric], Thick Film, General Purpose"
			(at 0 0 0)
			(layer "F.Fab")
			(hide yes)
			(effects
				(font
					(size 1.27 1.27)
					(thickness 0.15)
				)
			)
		)
		(property "Author" "Antmicro"
			(at 0 0 0)
			(layer "F.Fab")
			(hide yes)
			(effects
				(font
					(size 1 1)
					(thickness 0.15)
				)
			)
		)
		(property "Current" "1A"
			(at 0 0 0)
			(layer "F.Fab")
			(hide yes)
			(effects
				(font
					(size 1 1)
					(thickness 0.15)
				)
			)
		)
		(property "License" "Apache-2.0"
			(at 0 0 0)
			(layer "F.Fab")
			(hide yes)
			(effects
				(font
					(size 1 1)
					(thickness 0.15)
				)
			)
		)
		(property "MPN" "ERJ2GE0R00X"
			(at 0 0 0)
			(layer "F.Fab")
			(hide yes)
			(effects
				(font
					(size 1 1)
					(thickness 0.15)
				)
			)
		)
		(property "Manufacturer" "Panasonic"
			(at 0 0 0)
			(layer "F.Fab")
			(hide yes)
			(effects
				(font
					(size 1 1)
					(thickness 0.15)
				)
			)
		)
		(property "Tolerance" "~"
			(at 0 0 0)
			(layer "F.Fab")
			(hide yes)
			(effects
				(font
					(size 1 1)
					(thickness 0.15)
				)
			)
		)
		(property "Val" "0R"
			(at 0 0 0)
			(layer "F.Fab")
			(hide yes)
			(effects
				(font
					(size 1 1)
					(thickness 0.15)
				)
			)
		)
		(sheetname "/Peripherals/")
		(sheetfile "peripherals.kicad_sch")
		(attr smd)
		(fp_rect
			(start -0.925 -0.47)
			(end 0.925 0.47)
			(stroke
				(width 0.05)
				(type default)
			)
			(fill no)
			(layer "F.CrtYd")
		)
		(fp_rect
			(start -0.5 -0.25)
			(end 0.5 0.25)
			(stroke
				(width 0.15)
				(type solid)
			)
			(fill no)
			(layer "F.Fab")
		)
		(fp_text user "Author: Antmicro"
			(at -0.95 4.169 0)
			(layer "F.Fab")
			(effects
				(font
					(size 0.7 0.7)
					(thickness 0.15)
				)
				(justify left bottom)
			)
		)
		(fp_text user "${REFERENCE}"
			(at -0.95 3.168 0)
			(layer "F.Fab")
			(effects
				(font
					(size 0.7 0.7)
					(thickness 0.15)
				)
				(justify left bottom)
			)
		)
		(fp_text user "License: Apache-2.0"
			(at -0.95 5.169 0)
			(layer "F.Fab")
			(effects
				(font
					(size 0.7 0.7)
					(thickness 0.15)
				)
				(justify left bottom)
			)
		)
		(pad "1" smd roundrect
			(at -0.48 0)
			(size 0.59 0.64)
			(layers "F.Cu" "F.Mask" "F.Paste")
			(roundrect_rratio 0.25)
			(net 90 "/Peripherals/FFC1_VSYNC1")
			(pintype "passive")
		)
		(pad "2" smd roundrect
			(at 0.48 0)
			(size 0.59 0.64)
			(layers "F.Cu" "F.Mask" "F.Paste")
			(roundrect_rratio 0.25)
			(net 337 "Net-(J4-Pad34)")
			(pintype "passive")
		)
	)
	(footprint "antmicro-footprints:LED_0603_1608Metric_G"
		(layer "F.Cu")
		(at 141.46 84 180)
		(descr "LED SMD 0603 Green")
		(tags "LED SMD 0603 Green")
		(property "Reference" "D13"
			(at -3.27 0.36 0)
			(layer "F.SilkS")
			(effects
				(font
					(size 0.65 0.65)
					(thickness 0.15)
				)
				(justify right top)
			)
		)
		(property "Value" "LED_G_0603_LTST-C190GKT"
			(at 0 1.6 0)
			(layer "F.Fab")
			(hide yes)
			(effects
				(font
					(size 0.7 0.7)
					(thickness 0.15)
				)
				(justify right top)
			)
		)
		(property "Datasheet" "https://media.digikey.com/pdf/Data%20Sheets/Lite-On%20PDFs/LTST-C190GKT.pdf"
			(at 0 0 0)
			(layer "F.Fab")
			(hide yes)
			(effects
				(font
					(size 1.27 1.27)
					(thickness 0.15)
				)
			)
		)
		(property "Description" "LED, Green, SMD, 0603, 20 mA, 2.1 V, 569 nm"
			(at 0 0 0)
			(layer "F.Fab")
			(hide yes)
			(effects
				(font
					(size 1.27 1.27)
					(thickness 0.15)
				)
			)
		)
		(property "Author" "Antmicro"
			(at 0 0 0)
			(layer "F.Fab")
			(hide yes)
			(effects
				(font
					(size 1 1)
					(thickness 0.15)
				)
			)
		)
		(property "License" "Apache-2.0"
			(at 0 0 0)
			(layer "F.Fab")
			(hide yes)
			(effects
				(font
					(size 1 1)
					(thickness 0.15)
				)
			)
		)
		(property "MPN" "LTST-C190GKT"
			(at 0 0 0)
			(layer "F.Fab")
			(hide yes)
			(effects
				(font
					(size 1 1)
					(thickness 0.15)
				)
			)
		)
		(property "Manufacturer" "Lite-On"
			(at 0 0 0)
			(layer "F.Fab")
			(hide yes)
			(effects
				(font
					(size 1 1)
					(thickness 0.15)
				)
			)
		)
		(property "Color" "Green"
			(at 0 0 180)
			(unlocked yes)
			(layer "F.Fab")
			(hide yes)
			(effects
				(font
					(size 1 1)
					(thickness 0.15)
				)
			)
		)
		(sheetname "/Peripherals/")
		(sheetfile "peripherals.kicad_sch")
		(attr smd)
		(fp_line
			(start 0.22 0.35)
			(end -0.22 0.35)
			(stroke
				(width 0.15)
				(type solid)
			)
			(layer "F.SilkS")
		)
		(fp_line
			(start 0.22 -0.35)
			(end -0.22 -0.35)
			(stroke
				(width 0.15)
				(type solid)
			)
			(layer "F.SilkS")
		)
		(fp_line
			(start 0.105328 0.201008)
			(end 0.105328 -0.198992)
			(stroke
				(width 0.1)
				(type solid)
			)
			(layer "F.SilkS")
		)
		(fp_line
			(start 0.105328 0.201008)
			(end -0.094672 0.001008)
			(stroke
				(width 0.1)
				(type solid)
			)
			(layer "F.SilkS")
		)
		(fp_line
			(start 0.105328 0.001008)
			(end 0.24 0.001)
			(stroke
				(width 0.1)
				(type solid)
			)
			(layer "F.SilkS")
		)
		(fp_line
			(start -0.094672 0.201008)
			(end -0.094672 -0.198992)
			(stroke
				(width 0.1)
				(type solid)
			)
			(layer "F.SilkS")
		)
		(fp_line
			(start -0.094672 0.001008)
			(end 0.105328 -0.198992)
			(stroke
				(width 0.1)
				(type solid)
			)
			(layer "F.SilkS")
		)
		(fp_line
			(start -0.094672 0.001008)
			(end -0.24 0.001008)
			(stroke
				(width 0.1)
				(type solid)
			)
			(layer "F.SilkS")
		)
		(fp_line
			(start -1.18 -0.319)
			(end -1.18 0.321)
			(stroke
				(width 0.15)
				(type solid)
			)
			(layer "F.SilkS")
		)
		(fp_rect
			(start 1.25 0.65)
			(end -1.25 -0.65)
			(stroke
				(width 0.05)
				(type solid)
			)
			(fill no)
			(layer "F.CrtYd")
		)
		(fp_line
			(start 0.599 0)
			(end 0.201 0)
			(stroke
				(width 0.15)
				(type solid)
			)
			(layer "F.Fab")
		)
		(fp_line
			(start 0.201 0.2)
			(end 0.201 0)
			(stroke
				(width 0.15)
				(type solid)
			)
			(layer "F.Fab")
		)
		(fp_line
			(start 0.201 0)
			(end 0.201 -0.202)
			(stroke
				(width 0.15)
				(type solid)
			)
			(layer "F.Fab")
		)
		(fp_line
			(start 0.201 -0.202)
			(end -0.101 0)
			(stroke
				(width 0.15)
				(type solid)
			)
			(layer "F.Fab")
		)
		(fp_line
			(start -0.101 0)
			(end 0.201 0.2)
			(stroke
				(width 0.15)
				(type solid)
			)
			(layer "F.Fab")
		)
		(fp_line
			(start -0.199 0.2)
			(end -0.199 0.1)
			(stroke
				(width 0.15)
				(type solid)
			)
			(layer "F.Fab")
		)
		(fp_line
			(start -0.199 0)
			(end -0.597 0)
			(stroke
				(width 0.15)
				(type solid)
			)
			(layer "F.Fab")
		)
		(fp_line
			(start -0.199 -0.202)
			(end -0.199 0.1)
			(stroke
				(width 0.15)
				(type solid)
			)
			(layer "F.Fab")
		)
		(fp_rect
			(start 0.848 0.4)
			(end -0.85 -0.402)
			(stroke
				(width 0.15)
				(type solid)
			)
			(fill no)
			(layer "F.Fab")
		)
		(fp_text user "License: Apache-2.0"
			(at -1.4224 3.599 0)
			(layer "F.Fab")
			(effects
				(font
					(size 0.7 0.7)
					(thickness 0.15)
				)
				(justify right top)
			)
		)
		(fp_text user "Author: Antmicro"
			(at -1.4224 4.799 0)
			(layer "F.Fab")
			(effects
				(font
					(size 0.7 0.7)
					(thickness 0.15)
				)
				(justify right top)
			)
		)
		(fp_text user "${REFERENCE}"
			(at -1.4224 5.999 0)
			(layer "F.Fab")
			(effects
				(font
					(size 0.7 0.7)
					(thickness 0.15)
				)
				(justify right top)
			)
		)
		(pad "1" smd roundrect
			(at -0.7 0)
			(size 0.8 1)
			(layers "F.Cu" "F.Mask" "F.Paste")
			(roundrect_rratio 0.2)
			(net 296 "Net-(D13-C)")
			(pinfunction "C")
			(pintype "passive")
		)
		(pad "2" smd roundrect
			(at 0.7 0)
			(size 0.8 1)
			(layers "F.Cu" "F.Mask" "F.Paste")
			(roundrect_rratio 0.2)
			(net 295 "Net-(D13-A)")
			(pinfunction "A")
			(pintype "passive")
		)
	)
	(footprint "antmicro-footprints:C_0603_1608Metric"
		(layer "F.Cu")
		(at 160.63 60.19)
		(descr "Capacitor SMD 0603")
		(tags "capacitor 0603")
		(property "Reference" "C28"
			(at -0.55 -0.97 270)
			(layer "F.SilkS")
			(effects
				(font
					(size 0.65 0.65)
					(thickness 0.15)
				)
				(justify left bottom)
			)
		)
		(property "Value" "C_22u_0603"
			(at 0 1.6 0)
			(layer "F.Fab")
			(hide yes)
			(effects
				(font
					(size 0.7 0.7)
					(thickness 0.15)
				)
				(justify left bottom)
			)
		)
		(property "Datasheet" "https://www.murata.com/products/productdetail?partno=GRM188R60J226MEA0%23"
			(at 0 0 0)
			(layer "F.Fab")
			(hide yes)
			(effects
				(font
					(size 1.27 1.27)
					(thickness 0.15)
				)
			)
		)
		(property "Description" "SMD Multilayer Ceramic Capacitor, 22 µF, 6.3 V, 0603 [1608 Metric], ± 20%, X5R, GRM Series"
			(at 0 0 0)
			(layer "F.Fab")
			(hide yes)
			(effects
				(font
					(size 1.27 1.27)
					(thickness 0.15)
				)
			)
		)
		(property "Author" "Antmicro"
			(at 0 0 0)
			(layer "F.Fab")
			(hide yes)
			(effects
				(font
					(size 1 1)
					(thickness 0.15)
				)
			)
		)
		(property "Dielectric" ""
			(at 0 0 0)
			(layer "F.Fab")
			(hide yes)
			(effects
				(font
					(size 1 1)
					(thickness 0.15)
				)
			)
		)
		(property "License" "Apache-2.0"
			(at 0 0 0)
			(layer "F.Fab")
			(hide yes)
			(effects
				(font
					(size 1 1)
					(thickness 0.15)
				)
			)
		)
		(property "MPN" "GRM188R60J226MEA0D"
			(at 0 0 0)
			(layer "F.Fab")
			(hide yes)
			(effects
				(font
					(size 1 1)
					(thickness 0.15)
				)
			)
		)
		(property "Manufacturer" "Murata"
			(at 0 0 0)
			(layer "F.Fab")
			(hide yes)
			(effects
				(font
					(size 1 1)
					(thickness 0.15)
				)
			)
		)
		(property "Val" "22u"
			(at 0 0 0)
			(layer "F.Fab")
			(hide yes)
			(effects
				(font
					(size 1 1)
					(thickness 0.15)
				)
			)
		)
		(property "Voltage" ""
			(at 0 0 0)
			(layer "F.Fab")
			(hide yes)
			(effects
				(font
					(size 1 1)
					(thickness 0.15)
				)
			)
		)
		(sheetname "/Power Supply/")
		(sheetfile "supply.kicad_sch")
		(attr smd)
		(fp_line
			(start -0.15 -0.4)
			(end 0.15 -0.4)
			(stroke
				(width 0.15)
				(type solid)
			)
			(layer "F.SilkS")
		)
		(fp_line
			(start -0.15 0.4)
			(end 0.15 0.4)
			(stroke
				(width 0.15)
				(type solid)
			)
			(layer "F.SilkS")
		)
		(fp_rect
			(start -1.25 -0.65)
			(end 1.25 0.65)
			(stroke
				(width 0.05)
				(type solid)
			)
			(fill no)
			(layer "F.CrtYd")
		)
		(fp_rect
			(start -0.8 -0.4)
			(end 0.8 0.4)
			(stroke
				(width 0.15)
				(type solid)
			)
			(fill no)
			(layer "F.Fab")
		)
		(fp_text user "Author: Antmicro"
			(at -1.682 4.894 0)
			(layer "F.Fab")
			(effects
				(font
					(size 0.7 0.7)
					(thickness 0.15)
				)
				(justify left bottom)
			)
		)
		(fp_text user "${REFERENCE}"
			(at -1.682 3.895 0)
			(layer "F.Fab")
			(effects
				(font
					(size 0.7 0.7)
					(thickness 0.15)
				)
				(justify left bottom)
			)
		)
		(fp_text user "License: Apache-2.0"
			(at -1.682 5.895 0)
			(layer "F.Fab")
			(effects
				(font
					(size 0.7 0.7)
					(thickness 0.15)
				)
				(justify left bottom)
			)
		)
		(pad "1" smd roundrect
			(at -0.7 0)
			(size 0.8 1)
			(layers "F.Cu" "F.Mask" "F.Paste")
			(roundrect_rratio 0.2)
			(net 1 "GND")
			(pintype "passive")
		)
		(pad "2" smd roundrect
			(at 0.7 0)
			(size 0.8 1)
			(layers "F.Cu" "F.Mask" "F.Paste")
			(roundrect_rratio 0.2)
			(net 275 "/Power Supply/3V3_OUT")
			(pintype "passive")
		)
	)
	(footprint "antmicro-footprints:R_0603_1608Metric"
		(layer "F.Cu")
		(at 158.29 78.2)
		(descr "Resistor SMD 0603")
		(tags "resistor SMD 0603")
		(property "Reference" "R116"
			(at -4.06 0.54 0)
			(layer "F.SilkS")
			(effects
				(font
					(size 0.65 0.65)
					(thickness 0.15)
				)
				(justify left bottom)
			)
		)
		(property "Value" "R_0R_0603"
			(at 0 1.6 0)
			(layer "F.Fab")
			(hide yes)
			(effects
				(font
					(size 0.7 0.7)
					(thickness 0.15)
				)
				(justify left bottom)
			)
		)
		(property "Datasheet" "https://www.bourns.com/docs/product-datasheets/cr.pdf?sfvrsn=574d41f6_14"
			(at 0 0 0)
			(layer "F.Fab")
			(hide yes)
			(effects
				(font
					(size 1.27 1.27)
					(thickness 0.15)
				)
			)
		)
		(property "Description" "Zero Ohm Resistor, Jumper, 0603 [1608 Metric], Thick Film, 100 mW, 1 A, Surface Mount Device, CR"
			(at 0 0 0)
			(layer "F.Fab")
			(hide yes)
			(effects
				(font
					(size 1.27 1.27)
					(thickness 0.15)
				)
			)
		)
		(property "Author" "Antmicro"
			(at 0 0 0)
			(layer "F.Fab")
			(hide yes)
			(effects
				(font
					(size 1 1)
					(thickness 0.15)
				)
			)
		)
		(property "Current" "1A"
			(at 0 0 0)
			(layer "F.Fab")
			(hide yes)
			(effects
				(font
					(size 1 1)
					(thickness 0.15)
				)
			)
		)
		(property "License" "Apache-2.0"
			(at 0 0 0)
			(layer "F.Fab")
			(hide yes)
			(effects
				(font
					(size 1 1)
					(thickness 0.15)
				)
			)
		)
		(property "MPN" "CR0603-J/-000ELF"
			(at 0 0 0)
			(layer "F.Fab")
			(hide yes)
			(effects
				(font
					(size 1 1)
					(thickness 0.15)
				)
			)
		)
		(property "Manufacturer" "Bourns"
			(at 0 0 0)
			(layer "F.Fab")
			(hide yes)
			(effects
				(font
					(size 1 1)
					(thickness 0.15)
				)
			)
		)
		(property "Tolerance" "~"
			(at 0 0 0)
			(layer "F.Fab")
			(hide yes)
			(effects
				(font
					(size 1 1)
					(thickness 0.15)
				)
			)
		)
		(property "Val" "0R"
			(at 0 0 0)
			(layer "F.Fab")
			(hide yes)
			(effects
				(font
					(size 1 1)
					(thickness 0.15)
				)
			)
		)
		(sheetname "/Peripherals/")
		(sheetfile "peripherals.kicad_sch")
		(attr smd)
		(fp_line
			(start -0.15 -0.4)
			(end 0.15 -0.4)
			(stroke
				(width 0.15)
				(type solid)
			)
			(layer "F.SilkS")
		)
		(fp_line
			(start -0.15 0.4)
			(end 0.15 0.4)
			(stroke
				(width 0.15)
				(type solid)
			)
			(layer "F.SilkS")
		)
		(fp_rect
			(start -1.25 -0.65)
			(end 1.25 0.65)
			(stroke
				(width 0.05)
				(type solid)
			)
			(fill no)
			(layer "F.CrtYd")
		)
		(fp_rect
			(start -0.8 -0.4)
			(end 0.8 0.4)
			(stroke
				(width 0.15)
				(type solid)
			)
			(fill no)
			(layer "F.Fab")
		)
		(fp_text user "License: Apache-2.0"
			(at -1.25 5.9 0)
			(layer "F.Fab")
			(effects
				(font
					(size 0.7 0.7)
					(thickness 0.15)
				)
				(justify left bottom)
			)
		)
		(fp_text user "Author: Antmicro"
			(at -1.25 4.9 0)
			(layer "F.Fab")
			(effects
				(font
					(size 0.7 0.7)
					(thickness 0.15)
				)
				(justify left bottom)
			)
		)
		(fp_text user "${REFERENCE}"
			(at -1.25 3.898 0)
			(layer "F.Fab")
			(effects
				(font
					(size 0.7 0.7)
					(thickness 0.15)
				)
				(justify left bottom)
			)
		)
		(pad "1" smd roundrect
			(at -0.7 0)
			(size 0.8 1)
			(layers "F.Cu" "F.Mask" "F.Paste")
			(roundrect_rratio 0.2)
			(net 101 "SDA")
			(pintype "passive")
		)
		(pad "2" smd roundrect
			(at 0.7 0)
			(size 0.8 1)
			(layers "F.Cu" "F.Mask" "F.Paste")
			(roundrect_rratio 0.2)
			(net 312 "Net-(J8-Pad3)")
			(pintype "passive")
		)
	)
)
